(kicad_pcb
	(version 20241229)
	(generator "pcbnew")
	(generator_version "9.0")
	(general
		(thickness 1.61)
		(legacy_teardrops no)
	)
	(paper "A3")
	(title_block
		(title "SO-DIMM DDR5 Tester")
		(date "2025-11-26")
		(rev "1.3.0")
		(comment 9 "footprint 147 of 627 (J2), pads 259-266 of 266")
	)
	(layers
		(0 "F.Cu" signal)
		(4 "In1.Cu" power)
		(6 "In2.Cu" mixed)
		(8 "In3.Cu" power)
		(10 "In4.Cu" mixed)
		(12 "In5.Cu" power)
		(14 "In6.Cu" mixed)
		(16 "In7.Cu" power)
		(18 "In8.Cu" power)
		(20 "In9.Cu" mixed)
		(22 "In10.Cu" power)
		(2 "B.Cu" signal)
		(9 "F.Adhes" user "F.Adhesive")
		(11 "B.Adhes" user "B.Adhesive")
		(13 "F.Paste" user)
		(15 "B.Paste" user)
		(5 "F.SilkS" user "F.Silkscreen")
		(7 "B.SilkS" user "B.Silkscreen")
		(1 "F.Mask" user)
		(3 "B.Mask" user)
		(17 "Dwgs.User" user "User.Drawings")
		(19 "Cmts.User" user "User.Comments")
		(21 "Eco1.User" user "User.Eco1")
		(23 "Eco2.User" user "User.Eco2")
		(25 "Edge.Cuts" user)
		(27 "Margin" user)
		(31 "F.CrtYd" user "F.Courtyard")
		(29 "B.CrtYd" user "B.Courtyard")
		(35 "F.Fab" user)
		(33 "B.Fab" user)
	)
	(footprint "antmicro-footprints:Bus_DDR5_SODIMM_Amphenol_10161033-002RHLF"
		(layer "F.Cu")
		(at 139.780001 134.8375 180)
		(property "Reference" "J2"
			(at -35.119999 -13.0625 180)
			(layer "F.SilkS")
			(effects
				(font
					(size 0.7 0.7)
					(thickness 0.15)
				)
				(justify left bottom)
			)
		)
		(property "Value" "Bus_DDR5_SODIMM_Amphenol_10161033-002RHLF_CUSTOM_2xDetectPin"
			(at 0 13.5 180)
			(layer "F.Fab")
			(effects
				(font
					(size 0.7 0.7)
					(thickness 0.15)
				)
				(justify left bottom)
			)
		)
		(property "Datasheet" "https://cdn.amphenol-cs.com/media/wysiwyg/files/documentation/datasheet/ssio/ssio_ddr5_sodimm.pdf"
			(at 0 0 180)
			(layer "F.Fab")
			(hide yes)
			(effects
				(font
					(size 1.27 1.27)
					(thickness 0.15)
				)
			)
		)
		(property "Author" "Antmicro"
			(at 279.560002 269.675 0)
			(layer "F.Fab")
			(hide yes)
			(effects
				(font
					(size 1 1)
					(thickness 0.15)
				)
			)
		)
		(property "License" "Apache-2.0"
			(at 279.560002 269.675 0)
			(layer "F.Fab")
			(hide yes)
			(effects
				(font
					(size 1 1)
					(thickness 0.15)
				)
			)
		)
		(property "MPN" "10161033-002RHLF"
			(at 279.560002 269.675 0)
			(layer "F.Fab")
			(hide yes)
			(effects
				(font
					(size 1 1)
					(thickness 0.15)
				)
			)
		)
		(property "Manufacturer" "Amphenol"
			(at 279.560002 269.675 0)
			(layer "F.Fab")
			(hide yes)
			(effects
				(font
					(size 1 1)
					(thickness 0.15)
				)
			)
		)
		(sheetname "/DDR5 SODIMM/")
		(sheetfile "ddr5-sodimm.kicad_sch")
		(attr smd)
		(pad "257" smd rect
			(at -32.12 -11.365 180)
			(size 0.3 1.5)
			(layers "F.Cu" "F.Mask" "F.Paste")
			(net 1 "GND")
			(pinfunction "VSS")
			(pintype "passive")
		)
		(pad "258" smd rect
			(at -32.37 -3.965 180)
			(size 0.3 1.5)
			(layers "F.Cu" "F.Mask" "F.Paste")
			(net 1 "GND")
			(pinfunction "VSS")
			(pintype "passive")
		)
		(pad "259" smd rect
			(at -32.62 -11.365 180)
			(size 0.3 1.5)
			(layers "F.Cu" "F.Mask" "F.Paste")
			(net 288 "/DDR5 SODIMM/B.DQ30")
			(pinfunction "DQ30_B")
			(pintype "passive")
		)
		(pad "260" smd rect
			(at -32.87 -3.965 180)
			(size 0.3 1.5)
			(layers "F.Cu" "F.Mask" "F.Paste")
			(net 289 "/DDR5 SODIMM/B.DQ31")
			(pinfunction "DQ31_B")
			(pintype "passive")
		)
		(pad "261" smd rect
			(at -33.12 -11.365 180)
			(size 0.3 1.5)
			(layers "F.Cu" "F.Mask" "F.Paste")
			(net 1 "GND")
			(pinfunction "VSS")
			(pintype "passive")
		)
		(pad "262" smd rect
			(at -33.37 -3.965 180)
			(size 0.3 1.5)
			(layers "F.Cu" "F.Mask" "F.Paste")
			(net 1 "GND")
			(pinfunction "VSS")
			(pintype "passive")
		)
		(pad "SH" smd rect
			(at -33.795 3.735 180)
			(size 3.5 4.6)
			(layers "F.Cu" "F.Mask" "F.Paste")
			(net 1 "GND")
			(pintype "passive")
			(zone_connect 2)
		)
		(pad "SH" smd rect
			(at 33.805 3.735 180)
			(size 3.5 4.6)
			(layers "F.Cu" "F.Mask" "F.Paste")
			(net 1 "GND")
			(pintype "passive")
			(zone_connect 2)
		)
	)
)
